(kicad_pcb
	(version 20260206)
	(generator "pcbnew")
	(generator_version "10.0")
	(general
		(thickness 1.6)
		(legacy_teardrops no)
	)
	(paper "A4")
	(title_block
		(title "03242023_DA0F0TMBIJ0_F0T_Motherboard_J_brd_V01_OCP.brd")
		(comment 1 "Grand Teton / footprints 1718-1722 of 6105")
	)
	(layers
		(0 "F.Cu" signal "TOP")
		(4 "In1.Cu" signal "GND")
		(6 "In2.Cu" signal "IN1")
		(8 "In3.Cu" signal "GND1")
		(10 "In4.Cu" signal "IN2")
		(12 "In5.Cu" signal "GND2")
		(14 "In6.Cu" signal "IN3")
		(16 "In7.Cu" signal "GND3")
		(18 "In8.Cu" signal "VCC")
		(20 "In9.Cu" signal "VCC1")
		(22 "In10.Cu" signal "GND4")
		(24 "In11.Cu" signal "IN4")
		(26 "In12.Cu" signal "GND5")
		(28 "In13.Cu" signal "IN5")
		(30 "In14.Cu" signal "GND6")
		(32 "In15.Cu" signal "IN6")
		(34 "In16.Cu" signal "GND7")
		(2 "B.Cu" signal "BOTTOM")
		(9 "F.Adhes" user "F.Adhesive")
		(11 "B.Adhes" user "B.Adhesive")
		(13 "F.Paste" user "Package Geometry/Pastemask Top")
		(15 "B.Paste" user "Package Geometry/Pastemask Bottom")
		(5 "F.SilkS" user "Ref Des/Silkscreen Top")
		(7 "B.SilkS" user "Ref Des/Silkscreen Bottom")
		(1 "F.Mask" user "Board Geometry/Soldermask Top")
		(3 "B.Mask" user "Board Geometry/Soldermask Bottom")
		(17 "Dwgs.User" user "User.Drawings")
		(19 "Cmts.User" user "User.Comments")
		(21 "Eco1.User" user "User.Eco1")
		(23 "Eco2.User" user "User.Eco2")
		(25 "Edge.Cuts" user "Board Geometry/Outline")
		(27 "Margin" user)
		(31 "F.CrtYd" user "Package Geometry/Place Bound Top")
		(29 "B.CrtYd" user "Package Geometry/Place Bound Bottom")
		(35 "F.Fab" user "Ref Des/Assembly Top")
		(33 "B.Fab" user "Ref Des/Assembly Bottom")
	)
	(footprint ""
		(layer "F.Cu")
		(at 457.8477 -385.08432 90)
		(property "Reference" "PU181"
			(at 4.0894 -2.363216 0)
			(unlocked yes)
			(layer "F.SilkS")
			(effects
				(font
					(size 0.7874 0.5842)
					(thickness 0.1524)
				)
				(justify left)
			)
		)
		(property "Value" ""
			(at 0 0 90)
			(layer "F.Fab")
			(effects
				(font
					(size 1.27 1.27)
				)
			)
		)
		(duplicate_pad_numbers_are_jumpers no)
		(fp_line
			(start 1.549908 -2.050034)
			(end 0.5842 -2.050034)
			(stroke
				(width 0.1524)
				(type default)
			)
			(layer "F.SilkS")
		)
		(fp_line
			(start -0.5842 -2.050034)
			(end -1.549908 -2.050034)
			(stroke
				(width 0.1524)
				(type default)
			)
			(layer "F.SilkS")
		)
		(fp_line
			(start -1.549908 -2.050034)
			(end -1.549908 -1.9812)
			(stroke
				(width 0.1524)
				(type default)
			)
			(layer "F.SilkS")
		)
		(fp_line
			(start 1.549908 -1.9812)
			(end 1.549908 -2.050034)
			(stroke
				(width 0.1524)
				(type default)
			)
			(layer "F.SilkS")
		)
		(fp_line
			(start -1.549908 1.9812)
			(end -1.549908 2.050034)
			(stroke
				(width 0.1524)
				(type default)
			)
			(layer "F.SilkS")
		)
		(fp_line
			(start 1.549908 2.050034)
			(end 1.549908 1.9304)
			(stroke
				(width 0.1524)
				(type default)
			)
			(layer "F.SilkS")
		)
		(fp_line
			(start 0 2.050034)
			(end 1.549908 2.050034)
			(stroke
				(width 0.1524)
				(type default)
			)
			(layer "F.SilkS")
		)
		(fp_line
			(start -1.549908 2.050034)
			(end -0.5842 2.050034)
			(stroke
				(width 0.1524)
				(type default)
			)
			(layer "F.SilkS")
		)
		(fp_poly
			(pts
				(xy -2.9464 -2.208022) (xy -2.9464 -1.192022) (xy -1.9304 -1.700022)
			)
			(stroke
				(width 0)
				(type default)
			)
			(fill yes)
			(layer "F.SilkS")
		)
		(fp_line
			(start 1.549908 -2.050034)
			(end -1.549908 -2.050034)
			(stroke
				(width 0.1)
				(type default)
			)
			(layer "F.Fab")
		)
		(fp_line
			(start -1.549908 -2.050034)
			(end -1.549908 2.050034)
			(stroke
				(width 0.1)
				(type default)
			)
			(layer "F.Fab")
		)
		(fp_line
			(start 1.549908 2.050034)
			(end 1.549908 -2.050034)
			(stroke
				(width 0.1)
				(type default)
			)
			(layer "F.Fab")
		)
		(fp_line
			(start -1.549908 2.050034)
			(end 1.549908 2.050034)
			(stroke
				(width 0.1)
				(type default)
			)
			(layer "F.Fab")
		)
		(fp_poly
			(pts
				(xy -2.9464 -2.208022) (xy -2.9464 -1.192022) (xy -1.9304 -1.700022)
			)
			(stroke
				(width 0)
				(type default)
			)
			(fill yes)
			(layer "F.Fab")
		)
		(pad "1" smd circle
			(at -1.35001 -1.700022 90)
			(size 0 0)
			(layers "F.Cu" "F.Mask" "F.Paste")
			(net "SW_P5V_AUX_BST")
		)
		(pad "2" smd rect
			(at -1.400048 -1.199896 180)
			(size 0.1778 0.8128)
			(layers "F.Cu" "F.Mask" "F.Paste")
			(net "GND")
		)
		(pad "3" smd rect
			(at -1.400048 -0.8001 180)
			(size 0.1778 0.8128)
			(layers "F.Cu" "F.Mask" "F.Paste")
			(net "P5V_AUX_CS")
		)
		(pad "4" smd rect
			(at -1.400048 -0.40005 180)
			(size 0.1778 0.8128)
			(layers "F.Cu" "F.Mask" "F.Paste")
			(net "P5V_AUX_MODE")
		)
		(pad "5" smd rect
			(at -1.400048 0 180)
			(size 0.1778 0.8128)
			(layers "F.Cu" "F.Mask" "F.Paste")
			(net "P5V_AUX_REF")
		)
		(pad "6" smd rect
			(at -1.400048 0.40005 180)
			(size 0.1778 0.8128)
			(layers "F.Cu" "F.Mask" "F.Paste")
			(net "GND")
		)
		(pad "7" smd rect
			(at -1.400048 0.8001 180)
			(size 0.1778 0.8128)
			(layers "F.Cu" "F.Mask" "F.Paste")
			(net "P5V_AUX_FB")
		)
		(pad "8" smd rect
			(at -1.400048 1.199896 180)
			(size 0.1778 0.8128)
			(layers "F.Cu" "F.Mask" "F.Paste")
			(net "PWRGD_P3V3_AUX")
		)
		(pad "9" smd rect
			(at -1.400048 1.700022 180)
			(size 0.3048 0.8128)
			(layers "F.Cu" "F.Mask" "F.Paste")
			(net "PWRGD_P5V_AUX_R")
		)
		(pad "10" smd rect
			(at -0.299974 1.299972 90)
			(size 0.3048 2.0066)
			(layers "F.Cu" "F.Mask" "F.Paste")
			(net "SW_P5V_AUX_FLT")
		)
		(pad "11_18" smd circle
			(at 1.175004 0.275082 90)
			(size 0 0)
			(layers "F.Cu" "F.Mask" "F.Paste")
			(net "GND")
		)
		(pad "19" smd rect
			(at 1.400048 -1.700022)
			(size 0.3048 0.8128)
			(layers "F.Cu" "F.Mask" "F.Paste")
			(net "P5V_AUX_VCC")
		)
		(pad "20" smd rect
			(at 0.299974 -1.299972 90)
			(size 0.3048 2.0066)
			(layers "F.Cu" "F.Mask" "F.Paste")
			(net "SW_P5V_AUX_SW")
		)
		(pad "21" smd rect
			(at -0.299974 -1.299972 90)
			(size 0.3048 2.0066)
			(layers "F.Cu" "F.Mask" "F.Paste")
			(net "SW_P5V_AUX_FLT")
		)
	)
	(footprint ""
		(layer "F.Cu")
		(at 356.667308 -333.804514 -90)
		(property "Reference" "PC298_P0_2"
			(at 0 0 270)
			(layer "F.SilkS")
			(hide yes)
			(effects
				(font
					(size 1.27 1.27)
				)
			)
		)
		(property "Value" ""
			(at 0 0 270)
			(layer "F.Fab")
			(effects
				(font
					(size 1.27 1.27)
				)
			)
		)
		(duplicate_pad_numbers_are_jumpers no)
		(fp_line
			(start -0.7874 0.4064)
			(end -0.7874 -0.4064)
			(stroke
				(width 0.1524)
				(type default)
			)
			(layer "F.SilkS")
		)
		(fp_line
			(start 0.7874 0.4064)
			(end -0.7874 0.4064)
			(stroke
				(width 0.1524)
				(type default)
			)
			(layer "F.SilkS")
		)
		(fp_line
			(start -0.7874 -0.4064)
			(end 0.7874 -0.4064)
			(stroke
				(width 0.1524)
				(type default)
			)
			(layer "F.SilkS")
		)
		(fp_line
			(start 0.7874 -0.4064)
			(end 0.7874 0.4064)
			(stroke
				(width 0.1524)
				(type default)
			)
			(layer "F.SilkS")
		)
		(fp_line
			(start -0.67945 0.3048)
			(end -0.67945 -0.305054)
			(stroke
				(width 0.1)
				(type default)
			)
			(layer "F.Fab")
		)
		(fp_line
			(start -0.12065 0.3048)
			(end -0.67945 0.3048)
			(stroke
				(width 0.1)
				(type default)
			)
			(layer "F.Fab")
		)
		(fp_line
			(start 0.120396 0.3048)
			(end 0.120396 0.2794)
			(stroke
				(width 0.1)
				(type default)
			)
			(layer "F.Fab")
		)
		(fp_line
			(start 0.67945 0.3048)
			(end 0.120396 0.3048)
			(stroke
				(width 0.1)
				(type default)
			)
			(layer "F.Fab")
		)
		(fp_line
			(start -0.12065 0.2794)
			(end -0.12065 0.3048)
			(stroke
				(width 0.1)
				(type default)
			)
			(layer "F.Fab")
		)
		(fp_line
			(start 0.120396 0.2794)
			(end -0.12065 0.2794)
			(stroke
				(width 0.1)
				(type default)
			)
			(layer "F.Fab")
		)
		(fp_line
			(start -0.12065 -0.2794)
			(end 0.12065 -0.2794)
			(stroke
				(width 0.1)
				(type default)
			)
			(layer "F.Fab")
		)
		(fp_line
			(start 0.12065 -0.2794)
			(end 0.12065 -0.3048)
			(stroke
				(width 0.1)
				(type default)
			)
			(layer "F.Fab")
		)
		(fp_line
			(start 0.12065 -0.3048)
			(end 0.67945 -0.3048)
			(stroke
				(width 0.1)
				(type default)
			)
			(layer "F.Fab")
		)
		(fp_line
			(start 0.67945 -0.3048)
			(end 0.67945 0.3048)
			(stroke
				(width 0.1)
				(type default)
			)
			(layer "F.Fab")
		)
		(fp_line
			(start -0.67945 -0.305054)
			(end -0.12065 -0.305054)
			(stroke
				(width 0.1)
				(type default)
			)
			(layer "F.Fab")
		)
		(fp_line
			(start -0.12065 -0.305054)
			(end -0.12065 -0.2794)
			(stroke
				(width 0.1)
				(type default)
			)
			(layer "F.Fab")
		)
		(pad "1" smd circle
			(at -0.40005 0 270)
			(size 0 0)
			(layers "F.Cu" "F.Mask" "F.Paste")
			(net "SW_P12V_PVCCIN_CPU0_FLT")
		)
		(pad "2" smd circle
			(at 0.40005 0 270)
			(size 0 0)
			(layers "F.Cu" "F.Mask" "F.Paste")
			(net "GND")
		)
	)
	(footprint ""
		(layer "F.Cu")
		(at 216.1286 -119.1514 180)
		(property "Reference" "R4717"
			(at 0 0 180)
			(layer "F.SilkS")
			(hide yes)
			(effects
				(font
					(size 1.27 1.27)
				)
			)
		)
		(property "Value" ""
			(at 0 0 180)
			(layer "F.Fab")
			(effects
				(font
					(size 1.27 1.27)
				)
			)
		)
		(duplicate_pad_numbers_are_jumpers no)
		(fp_line
			(start 0.7874 0.4064)
			(end -0.7874 0.4064)
			(stroke
				(width 0.1524)
				(type default)
			)
			(layer "F.SilkS")
		)
		(fp_line
			(start 0.7874 -0.4064)
			(end 0.7874 0.4064)
			(stroke
				(width 0.1524)
				(type default)
			)
			(layer "F.SilkS")
		)
		(fp_line
			(start -0.7874 0.4064)
			(end -0.7874 -0.4064)
			(stroke
				(width 0.1524)
				(type default)
			)
			(layer "F.SilkS")
		)
		(fp_line
			(start -0.7874 -0.4064)
			(end 0.7874 -0.4064)
			(stroke
				(width 0.1524)
				(type default)
			)
			(layer "F.SilkS")
		)
		(fp_line
			(start 0.67945 0.3048)
			(end 0.120396 0.3048)
			(stroke
				(width 0.1)
				(type default)
			)
			(layer "F.Fab")
		)
		(fp_line
			(start 0.67945 -0.3048)
			(end 0.67945 0.3048)
			(stroke
				(width 0.1)
				(type default)
			)
			(layer "F.Fab")
		)
		(fp_line
			(start 0.12065 -0.2794)
			(end 0.12065 -0.3048)
			(stroke
				(width 0.1)
				(type default)
			)
			(layer "F.Fab")
		)
		(fp_line
			(start 0.12065 -0.3048)
			(end 0.67945 -0.3048)
			(stroke
				(width 0.1)
				(type default)
			)
			(layer "F.Fab")
		)
		(fp_line
			(start 0.120396 0.3048)
			(end 0.120396 0.2794)
			(stroke
				(width 0.1)
				(type default)
			)
			(layer "F.Fab")
		)
		(fp_line
			(start 0.120396 0.2794)
			(end -0.12065 0.2794)
			(stroke
				(width 0.1)
				(type default)
			)
			(layer "F.Fab")
		)
		(fp_line
			(start -0.12065 0.3048)
			(end -0.67945 0.3048)
			(stroke
				(width 0.1)
				(type default)
			)
			(layer "F.Fab")
		)
		(fp_line
			(start -0.12065 0.2794)
			(end -0.12065 0.3048)
			(stroke
				(width 0.1)
				(type default)
			)
			(layer "F.Fab")
		)
		(fp_line
			(start -0.12065 -0.2794)
			(end 0.12065 -0.2794)
			(stroke
				(width 0.1)
				(type default)
			)
			(layer "F.Fab")
		)
		(fp_line
			(start -0.12065 -0.305054)
			(end -0.12065 -0.2794)
			(stroke
				(width 0.1)
				(type default)
			)
			(layer "F.Fab")
		)
		(fp_line
			(start -0.67945 0.3048)
			(end -0.67945 -0.305054)
			(stroke
				(width 0.1)
				(type default)
			)
			(layer "F.Fab")
		)
		(fp_line
			(start -0.67945 -0.305054)
			(end -0.12065 -0.305054)
			(stroke
				(width 0.1)
				(type default)
			)
			(layer "F.Fab")
		)
		(pad "1" smd circle
			(at -0.40005 0 180)
			(size 0 0)
			(layers "F.Cu" "F.Mask" "F.Paste")
			(net "FM_AC_PWR_BTN_R_N")
		)
		(pad "2" smd circle
			(at 0.40005 0 180)
			(size 0 0)
			(layers "F.Cu" "F.Mask" "F.Paste")
			(net "FM_AC_PWR_BTN_PLD_N")
		)
	)
	(footprint ""
		(layer "F.Cu")
		(at 96.294448 -74.767694 -90)
		(property "Reference" "R3078"
			(at 0 0 270)
			(layer "F.SilkS")
			(hide yes)
			(effects
				(font
					(size 1.27 1.27)
				)
			)
		)
		(property "Value" ""
			(at 0 0 270)
			(layer "F.Fab")
			(effects
				(font
					(size 1.27 1.27)
				)
			)
		)
		(duplicate_pad_numbers_are_jumpers no)
		(fp_line
			(start -0.7874 0.4064)
			(end -0.7874 -0.4064)
			(stroke
				(width 0.1524)
				(type default)
			)
			(layer "F.SilkS")
		)
		(fp_line
			(start 0.7874 0.4064)
			(end -0.7874 0.4064)
			(stroke
				(width 0.1524)
				(type default)
			)
			(layer "F.SilkS")
		)
		(fp_line
			(start -0.7874 -0.4064)
			(end 0.7874 -0.4064)
			(stroke
				(width 0.1524)
				(type default)
			)
			(layer "F.SilkS")
		)
		(fp_line
			(start 0.7874 -0.4064)
			(end 0.7874 0.4064)
			(stroke
				(width 0.1524)
				(type default)
			)
			(layer "F.SilkS")
		)
		(fp_line
			(start -0.67945 0.3048)
			(end -0.67945 -0.305054)
			(stroke
				(width 0.1)
				(type default)
			)
			(layer "F.Fab")
		)
		(fp_line
			(start -0.12065 0.3048)
			(end -0.67945 0.3048)
			(stroke
				(width 0.1)
				(type default)
			)
			(layer "F.Fab")
		)
		(fp_line
			(start 0.120396 0.3048)
			(end 0.120396 0.2794)
			(stroke
				(width 0.1)
				(type default)
			)
			(layer "F.Fab")
		)
		(fp_line
			(start 0.67945 0.3048)
			(end 0.120396 0.3048)
			(stroke
				(width 0.1)
				(type default)
			)
			(layer "F.Fab")
		)
		(fp_line
			(start -0.12065 0.2794)
			(end -0.12065 0.3048)
			(stroke
				(width 0.1)
				(type default)
			)
			(layer "F.Fab")
		)
		(fp_line
			(start 0.120396 0.2794)
			(end -0.12065 0.2794)
			(stroke
				(width 0.1)
				(type default)
			)
			(layer "F.Fab")
		)
		(fp_line
			(start -0.12065 -0.2794)
			(end 0.12065 -0.2794)
			(stroke
				(width 0.1)
				(type default)
			)
			(layer "F.Fab")
		)
		(fp_line
			(start 0.12065 -0.2794)
			(end 0.12065 -0.3048)
			(stroke
				(width 0.1)
				(type default)
			)
			(layer "F.Fab")
		)
		(fp_line
			(start 0.12065 -0.3048)
			(end 0.67945 -0.3048)
			(stroke
				(width 0.1)
				(type default)
			)
			(layer "F.Fab")
		)
		(fp_line
			(start 0.67945 -0.3048)
			(end 0.67945 0.3048)
			(stroke
				(width 0.1)
				(type default)
			)
			(layer "F.Fab")
		)
		(fp_line
			(start -0.67945 -0.305054)
			(end -0.12065 -0.305054)
			(stroke
				(width 0.1)
				(type default)
			)
			(layer "F.Fab")
		)
		(fp_line
			(start -0.12065 -0.305054)
			(end -0.12065 -0.2794)
			(stroke
				(width 0.1)
				(type default)
			)
			(layer "F.Fab")
		)
		(pad "1" smd circle
			(at -0.40005 0 270)
			(size 0 0)
			(layers "F.Cu" "F.Mask" "F.Paste")
			(net "LED_FM_PCH_SLP_S3_N")
		)
		(pad "2" smd circle
			(at 0.40005 0 270)
			(size 0 0)
			(layers "F.Cu" "F.Mask" "F.Paste")
			(net "P3V3_AUX")
		)
	)
	(footprint ""
		(layer "F.Cu")
		(at 155.690824 -52.674012)
		(property "Reference" "C2018"
			(at 0 0 0)
			(layer "F.SilkS")
			(hide yes)
			(effects
				(font
					(size 1.27 1.27)
				)
			)
		)
		(property "Value" ""
			(at 0 0 0)
			(layer "F.Fab")
			(effects
				(font
					(size 1.27 1.27)
				)
			)
		)
		(duplicate_pad_numbers_are_jumpers no)
		(fp_line
			(start -0.7874 -0.4064)
			(end 0.7874 -0.4064)
			(stroke
				(width 0.1524)
				(type default)
			)
			(layer "F.SilkS")
		)
		(fp_line
			(start -0.7874 0.4064)
			(end -0.7874 -0.4064)
			(stroke
				(width 0.1524)
				(type default)
			)
			(layer "F.SilkS")
		)
		(fp_line
			(start 0.7874 -0.4064)
			(end 0.7874 0.4064)
			(stroke
				(width 0.1524)
				(type default)
			)
			(layer "F.SilkS")
		)
		(fp_line
			(start 0.7874 0.4064)
			(end -0.7874 0.4064)
			(stroke
				(width 0.1524)
				(type default)
			)
			(layer "F.SilkS")
		)
		(fp_line
			(start -0.67945 -0.305054)
			(end -0.12065 -0.305054)
			(stroke
				(width 0.1)
				(type default)
			)
			(layer "F.Fab")
		)
		(fp_line
			(start -0.67945 0.3048)
			(end -0.67945 -0.305054)
			(stroke
				(width 0.1)
				(type default)
			)
			(layer "F.Fab")
		)
		(fp_line
			(start -0.12065 -0.305054)
			(end -0.12065 -0.2794)
			(stroke
				(width 0.1)
				(type default)
			)
			(layer "F.Fab")
		)
		(fp_line
			(start -0.12065 -0.2794)
			(end 0.12065 -0.2794)
			(stroke
				(width 0.1)
				(type default)
			)
			(layer "F.Fab")
		)
		(fp_line
			(start -0.12065 0.2794)
			(end -0.12065 0.3048)
			(stroke
				(width 0.1)
				(type default)
			)
			(layer "F.Fab")
		)
		(fp_line
			(start -0.12065 0.3048)
			(end -0.67945 0.3048)
			(stroke
				(width 0.1)
				(type default)
			)
			(layer "F.Fab")
		)
		(fp_line
			(start 0.120396 0.2794)
			(end -0.12065 0.2794)
			(stroke
				(width 0.1)
				(type default)
			)
			(layer "F.Fab")
		)
		(fp_line
			(start 0.120396 0.3048)
			(end 0.120396 0.2794)
			(stroke
				(width 0.1)
				(type default)
			)
			(layer "F.Fab")
		)
		(fp_line
			(start 0.12065 -0.3048)
			(end 0.67945 -0.3048)
			(stroke
				(width 0.1)
				(type default)
			)
			(layer "F.Fab")
		)
		(fp_line
			(start 0.12065 -0.2794)
			(end 0.12065 -0.3048)
			(stroke
				(width 0.1)
				(type default)
			)
			(layer "F.Fab")
		)
		(fp_line
			(start 0.67945 -0.3048)
			(end 0.67945 0.3048)
			(stroke
				(width 0.1)
				(type default)
			)
			(layer "F.Fab")
		)
		(fp_line
			(start 0.67945 0.3048)
			(end 0.120396 0.3048)
			(stroke
				(width 0.1)
				(type default)
			)
			(layer "F.Fab")
		)
		(pad "1" smd circle
			(at -0.40005 0)
			(size 0 0)
			(layers "F.Cu" "F.Mask" "F.Paste")
			(net "P3V3")
		)
		(pad "2" smd circle
			(at 0.40005 0)
			(size 0 0)
			(layers "F.Cu" "F.Mask" "F.Paste")
			(net "GND")
		)
	)
)
